# S9S_MB_2U (Grand Teton) — schematic netlist excerpt (pin names and nets, part order shuffled) for the footprints in the layout excerpt that follows; sources: Cadence DE-HDL packaged netlist, KiCad conversion of 03242023_DA0F0TMBIJ0_F0T_Motherboard_J_brd_V01_OCP.brd

R4495  Q_RES  33.2 1% CHIP  pkg 0402LF  page 213 : A = OCP_SFF_CLK_OE_R_N ; B = OCP_SFF_CLK_OE_N
R3057  Q_RES  33.2 1% CHIP  pkg 0402LF  page 239 : A = JTAG_DBP_BMC_PREQ_R1_N ; B = JTAG_BMC_DBP_PREQ_N

(kicad_pcb
	(version 20260206)
	(generator "pcbnew")
	(generator_version "10.0")
	(general
		(thickness 1.6)
		(legacy_teardrops no)
	)
	(paper "A4")
	(title_block
		(title "03242023_DA0F0TMBIJ0_F0T_Motherboard_J_brd_V01_OCP.brd")
		(comment 1 "Grand Teton / footprints 4684-4685 of 6105")
	)
	(layers
		(0 "F.Cu" signal "TOP")
		(4 "In1.Cu" signal "GND")
		(6 "In2.Cu" signal "IN1")
		(8 "In3.Cu" signal "GND1")
		(10 "In4.Cu" signal "IN2")
		(12 "In5.Cu" signal "GND2")
		(14 "In6.Cu" signal "IN3")
		(16 "In7.Cu" signal "GND3")
		(18 "In8.Cu" signal "VCC")
		(20 "In9.Cu" signal "VCC1")
		(22 "In10.Cu" signal "GND4")
		(24 "In11.Cu" signal "IN4")
		(26 "In12.Cu" signal "GND5")
		(28 "In13.Cu" signal "IN5")
		(30 "In14.Cu" signal "GND6")
		(32 "In15.Cu" signal "IN6")
		(34 "In16.Cu" signal "GND7")
		(2 "B.Cu" signal "BOTTOM")
		(9 "F.Adhes" user "F.Adhesive")
		(11 "B.Adhes" user "B.Adhesive")
		(13 "F.Paste" user "Package Geometry/Pastemask Top")
		(15 "B.Paste" user "Package Geometry/Pastemask Bottom")
		(5 "F.SilkS" user "Ref Des/Silkscreen Top")
		(7 "B.SilkS" user "Ref Des/Silkscreen Bottom")
		(1 "F.Mask" user "Board Geometry/Soldermask Top")
		(3 "B.Mask" user "Board Geometry/Soldermask Bottom")
		(17 "Dwgs.User" user "User.Drawings")
		(19 "Cmts.User" user "User.Comments")
		(21 "Eco1.User" user "User.Eco1")
		(23 "Eco2.User" user "User.Eco2")
		(25 "Edge.Cuts" user "Board Geometry/Outline")
		(27 "Margin" user)
		(31 "F.CrtYd" user "Package Geometry/Place Bound Top")
		(29 "B.CrtYd" user "Package Geometry/Place Bound Bottom")
		(35 "F.Fab" user "Ref Des/Assembly Top")
		(33 "B.Fab" user "Ref Des/Assembly Bottom")
	)
	(footprint ""
		(layer "B.Cu")
		(at 229.33025 -117.960648 -90)
		(property "Reference" "R4495"
			(at 0 0 90)
			(layer "B.SilkS")
			(hide yes)
			(effects
				(font
					(size 1.27 1.27)
				)
				(justify mirror)
			)
		)
		(property "Value" ""
			(at 0 0 90)
			(layer "B.Fab")
			(effects
				(font
					(size 1.27 1.27)
				)
				(justify mirror)
			)
		)
		(duplicate_pad_numbers_are_jumpers no)
		(fp_line
			(start -0.7874 0.4064)
			(end 0.7874 0.4064)
			(stroke
				(width 0.1524)
				(type default)
			)
			(layer "B.SilkS")
		)
		(fp_line
			(start 0.7874 0.4064)
			(end 0.7874 -0.4064)
			(stroke
				(width 0.1524)
				(type default)
			)
			(layer "B.SilkS")
		)
		(fp_line
			(start -0.7874 -0.4064)
			(end -0.7874 0.4064)
			(stroke
				(width 0.1524)
				(type default)
			)
			(layer "B.SilkS")
		)
		(fp_line
			(start 0.7874 -0.4064)
			(end -0.7874 -0.4064)
			(stroke
				(width 0.1524)
				(type default)
			)
			(layer "B.SilkS")
		)
		(fp_line
			(start -0.67945 0.3048)
			(end -0.120396 0.3048)
			(stroke
				(width 0.1)
				(type default)
			)
			(layer "B.Fab")
		)
		(fp_line
			(start -0.120396 0.3048)
			(end -0.120396 0.2794)
			(stroke
				(width 0.1)
				(type default)
			)
			(layer "B.Fab")
		)
		(fp_line
			(start 0.12065 0.3048)
			(end 0.67945 0.3048)
			(stroke
				(width 0.1)
				(type default)
			)
			(layer "B.Fab")
		)
		(fp_line
			(start 0.67945 0.3048)
			(end 0.67945 -0.305054)
			(stroke
				(width 0.1)
				(type default)
			)
			(layer "B.Fab")
		)
		(fp_line
			(start -0.120396 0.2794)
			(end 0.12065 0.2794)
			(stroke
				(width 0.1)
				(type default)
			)
			(layer "B.Fab")
		)
		(fp_line
			(start 0.12065 0.2794)
			(end 0.12065 0.3048)
			(stroke
				(width 0.1)
				(type default)
			)
			(layer "B.Fab")
		)
		(fp_line
			(start -0.12065 -0.2794)
			(end -0.12065 -0.3048)
			(stroke
				(width 0.1)
				(type default)
			)
			(layer "B.Fab")
		)
		(fp_line
			(start 0.12065 -0.2794)
			(end -0.12065 -0.2794)
			(stroke
				(width 0.1)
				(type default)
			)
			(layer "B.Fab")
		)
		(fp_line
			(start -0.67945 -0.3048)
			(end -0.67945 0.3048)
			(stroke
				(width 0.1)
				(type default)
			)
			(layer "B.Fab")
		)
		(fp_line
			(start -0.12065 -0.3048)
			(end -0.67945 -0.3048)
			(stroke
				(width 0.1)
				(type default)
			)
			(layer "B.Fab")
		)
		(fp_line
			(start 0.12065 -0.305054)
			(end 0.12065 -0.2794)
			(stroke
				(width 0.1)
				(type default)
			)
			(layer "B.Fab")
		)
		(fp_line
			(start 0.67945 -0.305054)
			(end 0.12065 -0.305054)
			(stroke
				(width 0.1)
				(type default)
			)
			(layer "B.Fab")
		)
		(pad "1" smd circle
			(at 0.40005 0 90)
			(size 0 0)
			(layers "B.Cu" "B.Mask" "B.Paste")
			(net "OCP_SFF_CLK_OE_R_N")
		)
		(pad "2" smd circle
			(at -0.40005 0 90)
			(size 0 0)
			(layers "B.Cu" "B.Mask" "B.Paste")
			(net "OCP_SFF_CLK_OE_N")
		)
	)
	(footprint ""
		(layer "B.Cu")
		(at 145.415 -9.362948 -90)
		(property "Reference" "R3057"
			(at 0 0 90)
			(layer "B.SilkS")
			(hide yes)
			(effects
				(font
					(size 1.27 1.27)
				)
				(justify mirror)
			)
		)
		(property "Value" ""
			(at 0 0 90)
			(layer "B.Fab")
			(effects
				(font
					(size 1.27 1.27)
				)
				(justify mirror)
			)
		)
		(duplicate_pad_numbers_are_jumpers no)
		(fp_line
			(start -0.7874 0.4064)
			(end 0.7874 0.4064)
			(stroke
				(width 0.1524)
				(type default)
			)
			(layer "B.SilkS")
		)
		(fp_line
			(start 0.7874 0.4064)
			(end 0.7874 -0.4064)
			(stroke
				(width 0.1524)
				(type default)
			)
			(layer "B.SilkS")
		)
		(fp_line
			(start -0.7874 -0.4064)
			(end -0.7874 0.4064)
			(stroke
				(width 0.1524)
				(type default)
			)
			(layer "B.SilkS")
		)
		(fp_line
			(start 0.7874 -0.4064)
			(end -0.7874 -0.4064)
			(stroke
				(width 0.1524)
				(type default)
			)
			(layer "B.SilkS")
		)
		(fp_line
			(start -0.67945 0.3048)
			(end -0.120396 0.3048)
			(stroke
				(width 0.1)
				(type default)
			)
			(layer "B.Fab")
		)
		(fp_line
			(start -0.120396 0.3048)
			(end -0.120396 0.2794)
			(stroke
				(width 0.1)
				(type default)
			)
			(layer "B.Fab")
		)
		(fp_line
			(start 0.12065 0.3048)
			(end 0.67945 0.3048)
			(stroke
				(width 0.1)
				(type default)
			)
			(layer "B.Fab")
		)
		(fp_line
			(start 0.67945 0.3048)
			(end 0.67945 -0.305054)
			(stroke
				(width 0.1)
				(type default)
			)
			(layer "B.Fab")
		)
		(fp_line
			(start -0.120396 0.2794)
			(end 0.12065 0.2794)
			(stroke
				(width 0.1)
				(type default)
			)
			(layer "B.Fab")
		)
		(fp_line
			(start 0.12065 0.2794)
			(end 0.12065 0.3048)
			(stroke
				(width 0.1)
				(type default)
			)
			(layer "B.Fab")
		)
		(fp_line
			(start -0.12065 -0.2794)
			(end -0.12065 -0.3048)
			(stroke
				(width 0.1)
				(type default)
			)
			(layer "B.Fab")
		)
		(fp_line
			(start 0.12065 -0.2794)
			(end -0.12065 -0.2794)
			(stroke
				(width 0.1)
				(type default)
			)
			(layer "B.Fab")
		)
		(fp_line
			(start -0.67945 -0.3048)
			(end -0.67945 0.3048)
			(stroke
				(width 0.1)
				(type default)
			)
			(layer "B.Fab")
		)
		(fp_line
			(start -0.12065 -0.3048)
			(end -0.67945 -0.3048)
			(stroke
				(width 0.1)
				(type default)
			)
			(layer "B.Fab")
		)
		(fp_line
			(start 0.12065 -0.305054)
			(end 0.12065 -0.2794)
			(stroke
				(width 0.1)
				(type default)
			)
			(layer "B.Fab")
		)
		(fp_line
			(start 0.67945 -0.305054)
			(end 0.12065 -0.305054)
			(stroke
				(width 0.1)
				(type default)
			)
			(layer "B.Fab")
		)
		(pad "1" smd circle
			(at 0.40005 0 90)
			(size 0 0)
			(layers "B.Cu" "B.Mask" "B.Paste")
			(net "JTAG_DBP_BMC_PREQ_R1_N")
		)
		(pad "2" smd circle
			(at -0.40005 0 90)
			(size 0 0)
			(layers "B.Cu" "B.Mask" "B.Paste")
			(net "JTAG_BMC_DBP_PREQ_N")
		)
	)
)
